(kicad_pcb
	(version 20260206)
	(generator "pcbnew")
	(generator_version "10.0")
	(general
		(thickness 1.6)
		(legacy_teardrops no)
	)
	(paper "A4")
	(title_block
		(title "v1-chassis-manager — T6M_CM_d_v01_1031_1645.brd")
		(comment 1 "Open CloudServer (Microsoft) / footprints 514-521 of 2512")
	)
	(layers
		(0 "F.Cu" signal "TOP")
		(4 "In1.Cu" signal "GND1")
		(6 "In2.Cu" signal "IN1")
		(8 "In3.Cu" signal "VCC1")
		(10 "In4.Cu" signal "VCC2")
		(12 "In5.Cu" signal "GND2")
		(14 "In6.Cu" signal "IN2")
		(16 "In7.Cu" signal "IN3")
		(18 "In8.Cu" signal "GND3")
		(2 "B.Cu" signal "BOTTOM")
		(9 "F.Adhes" user "F.Adhesive")
		(11 "B.Adhes" user "B.Adhesive")
		(13 "F.Paste" user "Package Geometry/Pastemask Top")
		(15 "B.Paste" user "Package Geometry/Pastemask Bottom")
		(5 "F.SilkS" user "Ref Des/Silkscreen Top")
		(7 "B.SilkS" user "Ref Des/Silkscreen Bottom")
		(1 "F.Mask" user "Board Geometry/Soldermask Top")
		(3 "B.Mask" user "Board Geometry/Soldermask Bottom")
		(17 "Dwgs.User" user "User.Drawings")
		(19 "Cmts.User" user "User.Comments")
		(21 "Eco1.User" user "User.Eco1")
		(23 "Eco2.User" user "User.Eco2")
		(25 "Edge.Cuts" user "Board Geometry/Outline")
		(27 "Margin" user)
		(31 "F.CrtYd" user "Package Geometry/Place Bound Top")
		(29 "B.CrtYd" user "Package Geometry/Place Bound Bottom")
		(35 "F.Fab" user "Ref Des/Assembly Top")
		(33 "B.Fab" user "Ref Des/Assembly Bottom")
	)
	(footprint ""
		(layer "F.Cu")
		(at 126.644146 -164.228526 180)
		(property "Reference" "R684"
			(at 0.939546 4.341622 0)
			(unlocked yes)
			(layer "F.SilkS")
			(effects
				(font
					(size 0.7874 0.5842)
					(thickness 0.1524)
				)
				(justify left)
			)
		)
		(property "Value" ""
			(at 0 0 180)
			(layer "F.Fab")
			(effects
				(font
					(size 1.27 1.27)
				)
			)
		)
		(duplicate_pad_numbers_are_jumpers no)
		(fp_line
			(start 0.7874 0.4064)
			(end -0.7874 0.4064)
			(stroke
				(width 0.1524)
				(type default)
			)
			(layer "F.SilkS")
		)
		(fp_line
			(start 0.7874 -0.4064)
			(end 0.7874 0.4064)
			(stroke
				(width 0.1524)
				(type default)
			)
			(layer "F.SilkS")
		)
		(fp_line
			(start -0.7874 0.4064)
			(end -0.7874 -0.4064)
			(stroke
				(width 0.1524)
				(type default)
			)
			(layer "F.SilkS")
		)
		(fp_line
			(start -0.7874 -0.4064)
			(end 0.7874 -0.4064)
			(stroke
				(width 0.1524)
				(type default)
			)
			(layer "F.SilkS")
		)
		(fp_poly
			(pts
				(xy -0.508 0.2794) (xy -0.508 0.2286) (xy -0.635 0.2286) (xy -0.635 -0.254) (xy -0.5334 -0.254)
				(xy -0.5334 -0.2794) (xy 0.5334 -0.2794) (xy 0.5334 -0.254) (xy 0.635 -0.254) (xy 0.635 0.254) (xy 0.5334 0.254)
				(xy 0.5334 0.2794)
			)
			(stroke
				(width 0)
				(type default)
			)
			(fill no)
			(layer "F.CrtYd")
		)
		(pad "1" smd rect
			(at 0.40005 0 180)
			(size 0.4572 0.508)
			(layers "F.Cu" "F.Mask" "F.Paste")
			(net "CPLD123_RSV2")
		)
		(pad "2" smd rect
			(at -0.40005 0 180)
			(size 0.4572 0.508)
			(layers "F.Cu" "F.Mask" "F.Paste")
			(net "CPLD3_RSV2")
		)
	)
	(footprint ""
		(layer "F.Cu")
		(at 80.93456 -80.683608 -90)
		(property "Reference" "C82"
			(at 17.592294 -1.189482 90)
			(unlocked yes)
			(layer "F.SilkS")
			(effects
				(font
					(size 0.7874 0.5842)
					(thickness 0.1524)
				)
				(justify left)
			)
		)
		(property "Value" ""
			(at 0 0 270)
			(layer "F.Fab")
			(effects
				(font
					(size 1.27 1.27)
				)
			)
		)
		(duplicate_pad_numbers_are_jumpers no)
		(fp_line
			(start -0.7874 0.4064)
			(end -0.7874 -0.4064)
			(stroke
				(width 0.1524)
				(type default)
			)
			(layer "F.SilkS")
		)
		(fp_line
			(start 0.7874 0.4064)
			(end -0.7874 0.4064)
			(stroke
				(width 0.1524)
				(type default)
			)
			(layer "F.SilkS")
		)
		(fp_line
			(start 0 0.381)
			(end 0 -0.381)
			(stroke
				(width 0.1524)
				(type default)
			)
			(layer "F.SilkS")
		)
		(fp_line
			(start -0.7874 -0.4064)
			(end 0.7874 -0.4064)
			(stroke
				(width 0.1524)
				(type default)
			)
			(layer "F.SilkS")
		)
		(fp_line
			(start 0.7874 -0.4064)
			(end 0.7874 0.4064)
			(stroke
				(width 0.1524)
				(type default)
			)
			(layer "F.SilkS")
		)
		(fp_poly
			(pts
				(xy -0.5334 0.254) (xy -0.635 0.254) (xy -0.635 0.2286) (xy -0.635 -0.254) (xy -0.5334 -0.254) (xy -0.5334 -0.2794)
				(xy 0.5334 -0.2794) (xy 0.5334 -0.254) (xy 0.635 -0.254) (xy 0.635 0.254) (xy 0.5334 0.254) (xy 0.5334 0.2794)
				(xy -0.508 0.2794) (xy -0.5334 0.2794)
			)
			(stroke
				(width 0)
				(type default)
			)
			(fill no)
			(layer "F.CrtYd")
		)
		(pad "1" smd rect
			(at 0.40005 0 270)
			(size 0.4572 0.508)
			(layers "F.Cu" "F.Mask" "F.Paste")
			(net "PV_VCCP_NODE1")
		)
		(pad "2" smd rect
			(at -0.40005 0 270)
			(size 0.4572 0.508)
			(layers "F.Cu" "F.Mask" "F.Paste")
			(net "GND")
		)
	)
	(footprint ""
		(layer "F.Cu")
		(at 142.02156 -114.383058 90)
		(property "Reference" "R135"
			(at -1.995678 3.151632 90)
			(unlocked yes)
			(layer "F.SilkS")
			(effects
				(font
					(size 0.7874 0.5842)
					(thickness 0.1524)
				)
				(justify left)
			)
		)
		(property "Value" ""
			(at 0 0 90)
			(layer "F.Fab")
			(effects
				(font
					(size 1.27 1.27)
				)
			)
		)
		(duplicate_pad_numbers_are_jumpers no)
		(fp_line
			(start 0.7874 -0.4064)
			(end 0.7874 0.4064)
			(stroke
				(width 0.1524)
				(type default)
			)
			(layer "F.SilkS")
		)
		(fp_line
			(start -0.7874 -0.4064)
			(end 0.7874 -0.4064)
			(stroke
				(width 0.1524)
				(type default)
			)
			(layer "F.SilkS")
		)
		(fp_line
			(start 0.7874 0.4064)
			(end -0.7874 0.4064)
			(stroke
				(width 0.1524)
				(type default)
			)
			(layer "F.SilkS")
		)
		(fp_line
			(start -0.7874 0.4064)
			(end -0.7874 -0.4064)
			(stroke
				(width 0.1524)
				(type default)
			)
			(layer "F.SilkS")
		)
		(fp_poly
			(pts
				(xy -0.508 0.2794) (xy -0.508 0.2286) (xy -0.635 0.2286) (xy -0.635 -0.254) (xy -0.5334 -0.254)
				(xy -0.5334 -0.2794) (xy 0.5334 -0.2794) (xy 0.5334 -0.254) (xy 0.635 -0.254) (xy 0.635 0.254) (xy 0.5334 0.254)
				(xy 0.5334 0.2794)
			)
			(stroke
				(width 0)
				(type default)
			)
			(fill no)
			(layer "F.CrtYd")
		)
		(pad "1" smd rect
			(at 0.40005 0 90)
			(size 0.4572 0.508)
			(layers "F.Cu" "F.Mask" "F.Paste")
			(net "CLKREQC_NODE1_N")
		)
		(pad "2" smd rect
			(at -0.40005 0 90)
			(size 0.4572 0.508)
			(layers "F.Cu" "F.Mask" "F.Paste")
			(net "CLK_48M_SIO")
		)
	)
	(footprint ""
		(layer "F.Cu")
		(at 58.53176 -185.205624 -90)
		(property "Reference" "R946"
			(at -4.006088 0.281178 90)
			(unlocked yes)
			(layer "F.SilkS")
			(effects
				(font
					(size 0.7874 0.5842)
					(thickness 0.1524)
				)
				(justify left)
			)
		)
		(property "Value" ""
			(at 0 0 270)
			(layer "F.Fab")
			(effects
				(font
					(size 1.27 1.27)
				)
			)
		)
		(duplicate_pad_numbers_are_jumpers no)
		(fp_line
			(start -0.7874 0.4064)
			(end -0.7874 -0.4064)
			(stroke
				(width 0.1524)
				(type default)
			)
			(layer "F.SilkS")
		)
		(fp_line
			(start 0.7874 0.4064)
			(end -0.7874 0.4064)
			(stroke
				(width 0.1524)
				(type default)
			)
			(layer "F.SilkS")
		)
		(fp_line
			(start -0.7874 -0.4064)
			(end 0.7874 -0.4064)
			(stroke
				(width 0.1524)
				(type default)
			)
			(layer "F.SilkS")
		)
		(fp_line
			(start 0.7874 -0.4064)
			(end 0.7874 0.4064)
			(stroke
				(width 0.1524)
				(type default)
			)
			(layer "F.SilkS")
		)
		(fp_poly
			(pts
				(xy -0.508 0.2794) (xy -0.508 0.2286) (xy -0.635 0.2286) (xy -0.635 -0.254) (xy -0.5334 -0.254)
				(xy -0.5334 -0.2794) (xy 0.5334 -0.2794) (xy 0.5334 -0.254) (xy 0.635 -0.254) (xy 0.635 0.254) (xy 0.5334 0.254)
				(xy 0.5334 0.2794)
			)
			(stroke
				(width 0)
				(type default)
			)
			(fill no)
			(layer "F.CrtYd")
		)
		(pad "1" smd rect
			(at 0.40005 0 270)
			(size 0.4572 0.508)
			(layers "F.Cu" "F.Mask" "F.Paste")
			(net "UART_T2_NODE3_TXD")
		)
		(pad "2" smd rect
			(at -0.40005 0 270)
			(size 0.4572 0.508)
			(layers "F.Cu" "F.Mask" "F.Paste")
			(net "UART_T2_NODE3_TXD_R")
		)
	)
	(footprint ""
		(layer "F.Cu")
		(at 153.501852 -87.16899 -90)
		(property "Reference" "R528"
			(at 0.05461 3.688588 0)
			(unlocked yes)
			(layer "F.SilkS")
			(effects
				(font
					(size 0.7874 0.5842)
					(thickness 0.1524)
				)
				(justify left)
			)
		)
		(property "Value" ""
			(at 0 0 270)
			(layer "F.Fab")
			(effects
				(font
					(size 1.27 1.27)
				)
			)
		)
		(duplicate_pad_numbers_are_jumpers no)
		(fp_line
			(start -0.7874 0.4064)
			(end -0.7874 -0.4064)
			(stroke
				(width 0.1524)
				(type default)
			)
			(layer "F.SilkS")
		)
		(fp_line
			(start 0.7874 0.4064)
			(end -0.7874 0.4064)
			(stroke
				(width 0.1524)
				(type default)
			)
			(layer "F.SilkS")
		)
		(fp_line
			(start -0.7874 -0.4064)
			(end 0.7874 -0.4064)
			(stroke
				(width 0.1524)
				(type default)
			)
			(layer "F.SilkS")
		)
		(fp_line
			(start 0.7874 -0.4064)
			(end 0.7874 0.4064)
			(stroke
				(width 0.1524)
				(type default)
			)
			(layer "F.SilkS")
		)
		(fp_poly
			(pts
				(xy -0.508 0.2794) (xy -0.508 0.2286) (xy -0.635 0.2286) (xy -0.635 -0.254) (xy -0.5334 -0.254)
				(xy -0.5334 -0.2794) (xy 0.5334 -0.2794) (xy 0.5334 -0.254) (xy 0.635 -0.254) (xy 0.635 0.254) (xy 0.5334 0.254)
				(xy 0.5334 0.2794)
			)
			(stroke
				(width 0)
				(type default)
			)
			(fill no)
			(layer "F.CrtYd")
		)
		(pad "1" smd rect
			(at 0.40005 0 270)
			(size 0.4572 0.508)
			(layers "F.Cu" "F.Mask" "F.Paste")
			(net "P3V3_NODE1")
		)
		(pad "2" smd rect
			(at -0.40005 0 270)
			(size 0.4572 0.508)
			(layers "F.Cu" "F.Mask" "F.Paste")
			(net "SPI_USB_NODE1_WP_L")
		)
	)
	(footprint ""
		(layer "F.Cu")
		(at 140.31976 -115.863624)
		(property "Reference" "R15"
			(at -0.882396 -2.02438 0)
			(unlocked yes)
			(layer "F.SilkS")
			(effects
				(font
					(size 0.7874 0.5842)
					(thickness 0.1524)
				)
				(justify left)
			)
		)
		(property "Value" ""
			(at 0 0 0)
			(layer "F.Fab")
			(effects
				(font
					(size 1.27 1.27)
				)
			)
		)
		(duplicate_pad_numbers_are_jumpers no)
		(fp_line
			(start -0.7874 -0.4064)
			(end 0.7874 -0.4064)
			(stroke
				(width 0.1524)
				(type default)
			)
			(layer "F.SilkS")
		)
		(fp_line
			(start -0.7874 0.4064)
			(end -0.7874 -0.4064)
			(stroke
				(width 0.1524)
				(type default)
			)
			(layer "F.SilkS")
		)
		(fp_line
			(start 0.7874 -0.4064)
			(end 0.7874 0.4064)
			(stroke
				(width 0.1524)
				(type default)
			)
			(layer "F.SilkS")
		)
		(fp_line
			(start 0.7874 0.4064)
			(end -0.7874 0.4064)
			(stroke
				(width 0.1524)
				(type default)
			)
			(layer "F.SilkS")
		)
		(fp_poly
			(pts
				(xy -0.508 0.2794) (xy -0.508 0.2286) (xy -0.635 0.2286) (xy -0.635 -0.254) (xy -0.5334 -0.254)
				(xy -0.5334 -0.2794) (xy 0.5334 -0.2794) (xy 0.5334 -0.254) (xy 0.635 -0.254) (xy 0.635 0.254) (xy 0.5334 0.254)
				(xy 0.5334 0.2794)
			)
			(stroke
				(width 0)
				(type default)
			)
			(fill no)
			(layer "F.CrtYd")
		)
		(pad "1" smd rect
			(at 0.40005 0)
			(size 0.4572 0.508)
			(layers "F.Cu" "F.Mask" "F.Paste")
			(net "GND")
		)
		(pad "2" smd rect
			(at -0.40005 0)
			(size 0.4572 0.508)
			(layers "F.Cu" "F.Mask" "F.Paste")
			(net "CLKREQB_NODE1_N")
		)
	)
	(footprint ""
		(layer "F.Cu")
		(at 104.761792 -120.961404)
		(property "Reference" "PR75"
			(at -3.70205 -0.385572 0)
			(unlocked yes)
			(layer "F.SilkS")
			(effects
				(font
					(size 0.7874 0.5842)
					(thickness 0.1524)
				)
				(justify left)
			)
		)
		(property "Value" ""
			(at 0 0 0)
			(layer "F.Fab")
			(effects
				(font
					(size 1.27 1.27)
				)
			)
		)
		(duplicate_pad_numbers_are_jumpers no)
		(fp_line
			(start -0.4572 -0.44069)
			(end 0.4572 -0.44069)
			(stroke
				(width 0.1524)
				(type default)
			)
			(layer "F.SilkS")
		)
		(fp_line
			(start -0.4572 1.51511)
			(end -0.4572 -0.44069)
			(stroke
				(width 0.1524)
				(type default)
			)
			(layer "F.SilkS")
		)
		(fp_line
			(start -0.4572 1.54051)
			(end -0.4572 1.51511)
			(stroke
				(width 0.1524)
				(type default)
			)
			(layer "F.SilkS")
		)
		(fp_line
			(start 0.4572 -0.44069)
			(end 0.4572 1.54051)
			(stroke
				(width 0.1524)
				(type default)
			)
			(layer "F.SilkS")
		)
		(fp_line
			(start 0.4572 1.54051)
			(end -0.4572 1.54051)
			(stroke
				(width 0.1524)
				(type default)
			)
			(layer "F.SilkS")
		)
		(fp_poly
			(pts
				(xy 0.3556 0.37211) (xy 0.3556 -0.36449) (xy -0.3556 -0.36449) (xy -0.3556 1.46431) (xy 0.3556 1.46431)
				(xy 0.3556 0.72771)
			)
			(stroke
				(width 0)
				(type default)
			)
			(fill no)
			(layer "F.CrtYd")
		)
		(fp_line
			(start -0.299974 -0.025146)
			(end 0.299974 -0.025146)
			(stroke
				(width 0.1)
				(type default)
			)
			(layer "F.Fab")
		)
		(fp_line
			(start -0.299974 1.124966)
			(end -0.299974 -0.025146)
			(stroke
				(width 0.1)
				(type default)
			)
			(layer "F.Fab")
		)
		(fp_line
			(start 0.299974 -0.025146)
			(end 0.299974 1.124966)
			(stroke
				(width 0.1)
				(type default)
			)
			(layer "F.Fab")
		)
		(fp_line
			(start 0.299974 1.124966)
			(end -0.299974 1.124966)
			(stroke
				(width 0.1)
				(type default)
			)
			(layer "F.Fab")
		)
		(pad "1" smd rect
			(at 0 0 90)
			(size 0.6096 0.6096)
			(layers "F.Cu" "F.Mask" "F.Paste")
			(net "VR_PVCCP_NODE1_VCC")
		)
		(pad "2" smd rect
			(at 0 1.09982 90)
			(size 0.6096 0.6096)
			(layers "F.Cu" "F.Mask" "F.Paste")
			(net "VR_PVCCP_NODE1_TSEN_R")
		)
	)
	(footprint ""
		(layer "F.Cu")
		(at 62.663324 -99.685856 90)
		(property "Reference" "Q29"
			(at 4.319778 0.737616 0)
			(unlocked yes)
			(layer "F.SilkS")
			(effects
				(font
					(size 0.7874 0.5842)
					(thickness 0.1524)
				)
			)
		)
		(property "Value" ""
			(at 0 0 90)
			(layer "F.Fab")
			(effects
				(font
					(size 1.27 1.27)
				)
			)
		)
		(duplicate_pad_numbers_are_jumpers no)
		(fp_line
			(start 2.899918 -0.525018)
			(end 2.899918 -0.345694)
			(stroke
				(width 0.1524)
				(type default)
			)
			(layer "F.SilkS")
		)
		(fp_line
			(start 1.755648 -0.525018)
			(end 2.899918 -0.525018)
			(stroke
				(width 0.1524)
				(type default)
			)
			(layer "F.SilkS")
		)
		(fp_line
			(start -0.100076 -0.525018)
			(end 1.044448 -0.525018)
			(stroke
				(width 0.1524)
				(type default)
			)
			(layer "F.SilkS")
		)
		(fp_line
			(start -0.100076 -0.320294)
			(end -0.100076 -0.525018)
			(stroke
				(width 0.1524)
				(type default)
			)
			(layer "F.SilkS")
		)
		(fp_line
			(start 2.899918 2.295906)
			(end 2.899918 2.474976)
			(stroke
				(width 0.1524)
				(type default)
			)
			(layer "F.SilkS")
		)
		(fp_line
			(start 2.899918 2.474976)
			(end 1.755648 2.474976)
			(stroke
				(width 0.1524)
				(type default)
			)
			(layer "F.SilkS")
		)
		(fp_line
			(start 1.044448 2.474976)
			(end -0.100076 2.474976)
			(stroke
				(width 0.1524)
				(type default)
			)
			(layer "F.SilkS")
		)
		(fp_line
			(start -0.100076 2.474976)
			(end -0.100076 2.295906)
			(stroke
				(width 0.1524)
				(type default)
			)
			(layer "F.SilkS")
		)
		(fp_poly
			(pts
				(xy -0.99695 0.26924) (xy -0.99695 -0.249682) (xy -0.419608 0.01397)
			)
			(stroke
				(width 0)
				(type default)
			)
			(fill yes)
			(layer "F.SilkS")
		)
		(fp_poly
			(pts
				(xy -0.100076 -0.525018) (xy -0.100076 -0.244094) (xy -0.301752 -0.244094) (xy -0.301752 2.194306)
				(xy -0.100076 2.194306) (xy -0.100076 2.474976) (xy 1.120648 2.474976) (xy 1.120648 2.651506) (xy 1.679448 2.651506)
				(xy 1.679448 2.474976) (xy 2.899918 2.474976) (xy 2.899918 2.219706) (xy 3.101848 2.219706) (xy 3.101848 -0.269494)
				(xy 2.899918 -0.269494) (xy 2.899918 -0.525018) (xy 1.679448 -0.525018) (xy 1.679448 -0.701294)
				(xy 1.120648 -0.701294) (xy 1.120648 -0.525018)
			)
			(stroke
				(width 0)
				(type default)
			)
			(fill no)
			(layer "F.CrtYd")
		)
		(fp_line
			(start 2.899918 -0.525018)
			(end 2.899918 2.474976)
			(stroke
				(width 0.1)
				(type default)
			)
			(layer "F.Fab")
		)
		(fp_line
			(start -0.100076 -0.525018)
			(end 2.899918 -0.525018)
			(stroke
				(width 0.1)
				(type default)
			)
			(layer "F.Fab")
		)
		(fp_line
			(start 2.899918 2.474976)
			(end -0.100076 2.474976)
			(stroke
				(width 0.1)
				(type default)
			)
			(layer "F.Fab")
		)
		(fp_line
			(start -0.100076 2.474976)
			(end -0.100076 -0.525018)
			(stroke
				(width 0.1)
				(type default)
			)
			(layer "F.Fab")
		)
		(pad "1" smd rect
			(at 0 0)
			(size 0.3556 0.508)
			(layers "F.Cu" "F.Mask" "F.Paste")
			(net "P1V8_SUS_NODE1")
		)
		(pad "2" smd rect
			(at 0 0.649986)
			(size 0.3556 0.508)
			(layers "F.Cu" "F.Mask" "F.Paste")
			(net "P1V8_SUS_NODE1")
		)
		(pad "3" smd rect
			(at 0 1.299972)
			(size 0.3556 0.508)
			(layers "F.Cu" "F.Mask" "F.Paste")
			(net "P1V8_SUS_NODE1")
		)
		(pad "4" smd rect
			(at 0 1.949958)
			(size 0.3556 0.508)
			(layers "F.Cu" "F.Mask" "F.Paste")
			(net "FM_CPLD_NODE1_P1V8_SUS_EN_LV")
		)
		(pad "5" smd custom
			(at 1.400048 0.975106)
			(size 0.569976 0.569976)
			(layers "F.Cu" "F.Mask" "F.Paste")
			(net "P1V8_STB_NODE1")
			(options
				(clearance outline)
				(anchor circle)
			)
			(primitives
				(gr_poly
					(pts
						(xy -1.225042 1.139952) (xy -1.225042 0.724916) (xy -1.605026 0.724916) (xy -1.605026 0.295148)
						(xy -1.225042 0.295148) (xy -1.225042 -0.839978) (xy -1.175004 -0.839978) (xy -1.175004 -1.139952)
						(xy -0.774954 -1.139952) (xy -0.774954 -0.839978) (xy -0.525018 -0.839978) (xy -0.525018 -1.139952)
						(xy -0.124968 -1.139952) (xy -0.124968 -0.839978) (xy 0.124968 -0.839978) (xy 0.124968 -1.139952)
						(xy 0.525018 -1.139952) (xy 0.525018 -0.839978) (xy 0.774954 -0.839978) (xy 0.774954 -1.139952)
						(xy 1.175004 -1.139952) (xy 1.175004 -0.839978) (xy 1.225042 -0.839978) (xy 1.225042 0.295148)
						(xy 1.605026 0.295148) (xy 1.605026 0.724916) (xy 1.225042 0.724916) (xy 1.225042 1.139952)
					)
					(width 0)
					(fill yes)
				)
			)
		)
		(zone
			(layer "F.Cu")
			(hatch none 0.5)
			(connect_pads
				(clearance 0)
			)
			(min_thickness 0.25)
			(keepout
				(tracks allowed)
				(vias not_allowed)
				(pads allowed)
				(copperpour not_allowed)
				(footprints allowed)
			)
			(placement
				(enabled no)
				(sheetname "")
			)
			(fill
				(thermal_gap 0.5)
				(thermal_bridge_width 0.5)
				(island_removal_mode 0)
			)
			(polygon
				(pts
					(xy 62.13983 -100.400104) (xy 65.13703 -100.400104) (xy 65.13703 -100.019104) (xy 62.13983 -100.019104)
				)
			)
		)
		(zone
			(layer "F.Cu")
			(hatch none 0.5)
			(connect_pads
				(clearance 0)
			)
			(min_thickness 0.25)
			(keepout
				(tracks not_allowed)
				(vias allowed)
				(pads allowed)
				(copperpour not_allowed)
				(footprints allowed)
			)
			(placement
				(enabled no)
				(sheetname "")
			)
			(fill
				(thermal_gap 0.5)
				(thermal_bridge_width 0.5)
				(island_removal_mode 0)
			)
			(polygon
				(pts
					(xy 62.13983 -100.019104) (xy 65.13703 -100.019104) (xy 65.13703 -100.400104) (xy 62.13983 -100.400104)
				)
			)
		)
	)
)
